0.01000 T01
0.01200 T02
0.02800 T03
0.07100 T04
0.08600 T05
0.09300 T06
0.13900 T07
